(kicad_pcb
	(version 20260206)
	(generator "pcbnew")
	(generator_version "10.0")
	(general
		(thickness 1.6)
		(legacy_teardrops no)
	)
	(paper "A4")
	(title_block
		(title "12092022_DA0F0TMDCD0_F0T_Management_Board_D_brd_V3_OCP.brd")
		(comment 1 "Grand Teton / footprints 1153-1159 of 1440")
	)
	(layers
		(0 "F.Cu" signal "TOP")
		(4 "In1.Cu" signal "GND")
		(6 "In2.Cu" signal "IN1")
		(8 "In3.Cu" signal "GND1")
		(10 "In4.Cu" signal "IN2")
		(12 "In5.Cu" signal "VCC")
		(14 "In6.Cu" signal "VCC1")
		(16 "In7.Cu" signal "IN3")
		(18 "In8.Cu" signal "GND2")
		(20 "In9.Cu" signal "IN4")
		(22 "In10.Cu" signal "GND3")
		(2 "B.Cu" signal "BOTTOM")
		(9 "F.Adhes" user "F.Adhesive")
		(11 "B.Adhes" user "B.Adhesive")
		(13 "F.Paste" user "Package Geometry/Pastemask Top")
		(15 "B.Paste" user "Package Geometry/Pastemask Bottom")
		(5 "F.SilkS" user "Ref Des/Silkscreen Top")
		(7 "B.SilkS" user "Ref Des/Silkscreen Bottom")
		(1 "F.Mask" user "Board Geometry/Soldermask Top")
		(3 "B.Mask" user "Board Geometry/Soldermask Bottom")
		(17 "Dwgs.User" user "User.Drawings")
		(19 "Cmts.User" user "User.Comments")
		(21 "Eco1.User" user "User.Eco1")
		(23 "Eco2.User" user "User.Eco2")
		(25 "Edge.Cuts" user "Board Geometry/Outline")
		(27 "Margin" user)
		(31 "F.CrtYd" user "Package Geometry/Place Bound Top")
		(29 "B.CrtYd" user "Package Geometry/Place Bound Bottom")
		(35 "F.Fab" user "Ref Des/Assembly Top")
		(33 "B.Fab" user "Ref Des/Assembly Bottom")
	)
	(footprint ""
		(layer "B.Cu")
		(at 56.261 -16.764 90)
		(property "Reference" "R707"
			(at 0 0 90)
			(layer "B.SilkS")
			(hide yes)
			(effects
				(font
					(size 1.27 1.27)
				)
				(justify mirror)
			)
		)
		(property "Value" ""
			(at 0 0 90)
			(layer "B.Fab")
			(effects
				(font
					(size 1.27 1.27)
				)
				(justify mirror)
			)
		)
		(duplicate_pad_numbers_are_jumpers no)
		(fp_line
			(start 0.7874 -0.4064)
			(end -0.7874 -0.4064)
			(stroke
				(width 0.1524)
				(type default)
			)
			(layer "B.SilkS")
		)
		(fp_line
			(start -0.7874 -0.4064)
			(end -0.7874 0.4064)
			(stroke
				(width 0.1524)
				(type default)
			)
			(layer "B.SilkS")
		)
		(fp_line
			(start 0.7874 0.4064)
			(end 0.7874 -0.4064)
			(stroke
				(width 0.1524)
				(type default)
			)
			(layer "B.SilkS")
		)
		(fp_line
			(start -0.7874 0.4064)
			(end 0.7874 0.4064)
			(stroke
				(width 0.1524)
				(type default)
			)
			(layer "B.SilkS")
		)
		(fp_line
			(start 0.67945 -0.305054)
			(end 0.12065 -0.305054)
			(stroke
				(width 0.1)
				(type default)
			)
			(layer "B.Fab")
		)
		(fp_line
			(start 0.12065 -0.305054)
			(end 0.12065 -0.2794)
			(stroke
				(width 0.1)
				(type default)
			)
			(layer "B.Fab")
		)
		(fp_line
			(start -0.12065 -0.3048)
			(end -0.67945 -0.3048)
			(stroke
				(width 0.1)
				(type default)
			)
			(layer "B.Fab")
		)
		(fp_line
			(start -0.67945 -0.3048)
			(end -0.67945 0.3048)
			(stroke
				(width 0.1)
				(type default)
			)
			(layer "B.Fab")
		)
		(fp_line
			(start 0.12065 -0.2794)
			(end -0.12065 -0.2794)
			(stroke
				(width 0.1)
				(type default)
			)
			(layer "B.Fab")
		)
		(fp_line
			(start -0.12065 -0.2794)
			(end -0.12065 -0.3048)
			(stroke
				(width 0.1)
				(type default)
			)
			(layer "B.Fab")
		)
		(fp_line
			(start 0.12065 0.2794)
			(end 0.12065 0.3048)
			(stroke
				(width 0.1)
				(type default)
			)
			(layer "B.Fab")
		)
		(fp_line
			(start -0.120396 0.2794)
			(end 0.12065 0.2794)
			(stroke
				(width 0.1)
				(type default)
			)
			(layer "B.Fab")
		)
		(fp_line
			(start 0.67945 0.3048)
			(end 0.67945 -0.305054)
			(stroke
				(width 0.1)
				(type default)
			)
			(layer "B.Fab")
		)
		(fp_line
			(start 0.12065 0.3048)
			(end 0.67945 0.3048)
			(stroke
				(width 0.1)
				(type default)
			)
			(layer "B.Fab")
		)
		(fp_line
			(start -0.120396 0.3048)
			(end -0.120396 0.2794)
			(stroke
				(width 0.1)
				(type default)
			)
			(layer "B.Fab")
		)
		(fp_line
			(start -0.67945 0.3048)
			(end -0.120396 0.3048)
			(stroke
				(width 0.1)
				(type default)
			)
			(layer "B.Fab")
		)
		(pad "1" smd circle
			(at 0.40005 0 270)
			(size 0 0)
			(layers "B.Cu" "B.Mask" "B.Paste")
			(net "FM_DEBUG_PORT_R_PRSNT_N")
		)
		(pad "2" smd circle
			(at -0.40005 0 270)
			(size 0 0)
			(layers "B.Cu" "B.Mask" "B.Paste")
			(net "FM_DEBUG_PORT_PRSNT_N")
		)
	)
	(footprint ""
		(layer "B.Cu")
		(at 22.5552 -106.5022 -90)
		(property "Reference" "R828"
			(at 0 0 90)
			(layer "B.SilkS")
			(hide yes)
			(effects
				(font
					(size 1.27 1.27)
				)
				(justify mirror)
			)
		)
		(property "Value" ""
			(at 0 0 90)
			(layer "B.Fab")
			(effects
				(font
					(size 1.27 1.27)
				)
				(justify mirror)
			)
		)
		(duplicate_pad_numbers_are_jumpers no)
		(fp_line
			(start -0.7874 0.4064)
			(end 0.7874 0.4064)
			(stroke
				(width 0.1524)
				(type default)
			)
			(layer "B.SilkS")
		)
		(fp_line
			(start 0.7874 0.4064)
			(end 0.7874 -0.4064)
			(stroke
				(width 0.1524)
				(type default)
			)
			(layer "B.SilkS")
		)
		(fp_line
			(start -0.7874 -0.4064)
			(end -0.7874 0.4064)
			(stroke
				(width 0.1524)
				(type default)
			)
			(layer "B.SilkS")
		)
		(fp_line
			(start 0.7874 -0.4064)
			(end -0.7874 -0.4064)
			(stroke
				(width 0.1524)
				(type default)
			)
			(layer "B.SilkS")
		)
		(fp_line
			(start -0.67945 0.3048)
			(end -0.120396 0.3048)
			(stroke
				(width 0.1)
				(type default)
			)
			(layer "B.Fab")
		)
		(fp_line
			(start -0.120396 0.3048)
			(end -0.120396 0.2794)
			(stroke
				(width 0.1)
				(type default)
			)
			(layer "B.Fab")
		)
		(fp_line
			(start 0.12065 0.3048)
			(end 0.67945 0.3048)
			(stroke
				(width 0.1)
				(type default)
			)
			(layer "B.Fab")
		)
		(fp_line
			(start 0.67945 0.3048)
			(end 0.67945 -0.305054)
			(stroke
				(width 0.1)
				(type default)
			)
			(layer "B.Fab")
		)
		(fp_line
			(start -0.120396 0.2794)
			(end 0.12065 0.2794)
			(stroke
				(width 0.1)
				(type default)
			)
			(layer "B.Fab")
		)
		(fp_line
			(start 0.12065 0.2794)
			(end 0.12065 0.3048)
			(stroke
				(width 0.1)
				(type default)
			)
			(layer "B.Fab")
		)
		(fp_line
			(start -0.12065 -0.2794)
			(end -0.12065 -0.3048)
			(stroke
				(width 0.1)
				(type default)
			)
			(layer "B.Fab")
		)
		(fp_line
			(start 0.12065 -0.2794)
			(end -0.12065 -0.2794)
			(stroke
				(width 0.1)
				(type default)
			)
			(layer "B.Fab")
		)
		(fp_line
			(start -0.67945 -0.3048)
			(end -0.67945 0.3048)
			(stroke
				(width 0.1)
				(type default)
			)
			(layer "B.Fab")
		)
		(fp_line
			(start -0.12065 -0.3048)
			(end -0.67945 -0.3048)
			(stroke
				(width 0.1)
				(type default)
			)
			(layer "B.Fab")
		)
		(fp_line
			(start 0.12065 -0.305054)
			(end 0.12065 -0.2794)
			(stroke
				(width 0.1)
				(type default)
			)
			(layer "B.Fab")
		)
		(fp_line
			(start 0.67945 -0.305054)
			(end 0.12065 -0.305054)
			(stroke
				(width 0.1)
				(type default)
			)
			(layer "B.Fab")
		)
		(pad "1" smd circle
			(at 0.40005 0 90)
			(size 0 0)
			(layers "B.Cu" "B.Mask" "B.Paste")
			(net "P3V3_AUX")
		)
		(pad "2" smd circle
			(at -0.40005 0 90)
			(size 0 0)
			(layers "B.Cu" "B.Mask" "B.Paste")
			(net "RST_ROT_CPU_N")
		)
	)
	(footprint ""
		(layer "B.Cu")
		(at 15.24 -26.67 -90)
		(property "Reference" "C274"
			(at 0 0 90)
			(layer "B.SilkS")
			(hide yes)
			(effects
				(font
					(size 1.27 1.27)
				)
				(justify mirror)
			)
		)
		(property "Value" ""
			(at 0 0 90)
			(layer "B.Fab")
			(effects
				(font
					(size 1.27 1.27)
				)
				(justify mirror)
			)
		)
		(duplicate_pad_numbers_are_jumpers no)
		(fp_line
			(start -0.7874 0.4064)
			(end 0.7874 0.4064)
			(stroke
				(width 0.1524)
				(type default)
			)
			(layer "B.SilkS")
		)
		(fp_line
			(start 0.7874 0.4064)
			(end 0.7874 -0.4064)
			(stroke
				(width 0.1524)
				(type default)
			)
			(layer "B.SilkS")
		)
		(fp_line
			(start -0.7874 -0.4064)
			(end -0.7874 0.4064)
			(stroke
				(width 0.1524)
				(type default)
			)
			(layer "B.SilkS")
		)
		(fp_line
			(start 0.7874 -0.4064)
			(end -0.7874 -0.4064)
			(stroke
				(width 0.1524)
				(type default)
			)
			(layer "B.SilkS")
		)
		(fp_line
			(start -0.67945 0.3048)
			(end -0.120396 0.3048)
			(stroke
				(width 0.1)
				(type default)
			)
			(layer "B.Fab")
		)
		(fp_line
			(start -0.120396 0.3048)
			(end -0.120396 0.2794)
			(stroke
				(width 0.1)
				(type default)
			)
			(layer "B.Fab")
		)
		(fp_line
			(start 0.12065 0.3048)
			(end 0.67945 0.3048)
			(stroke
				(width 0.1)
				(type default)
			)
			(layer "B.Fab")
		)
		(fp_line
			(start 0.67945 0.3048)
			(end 0.67945 -0.305054)
			(stroke
				(width 0.1)
				(type default)
			)
			(layer "B.Fab")
		)
		(fp_line
			(start -0.120396 0.2794)
			(end 0.12065 0.2794)
			(stroke
				(width 0.1)
				(type default)
			)
			(layer "B.Fab")
		)
		(fp_line
			(start 0.12065 0.2794)
			(end 0.12065 0.3048)
			(stroke
				(width 0.1)
				(type default)
			)
			(layer "B.Fab")
		)
		(fp_line
			(start -0.12065 -0.2794)
			(end -0.12065 -0.3048)
			(stroke
				(width 0.1)
				(type default)
			)
			(layer "B.Fab")
		)
		(fp_line
			(start 0.12065 -0.2794)
			(end -0.12065 -0.2794)
			(stroke
				(width 0.1)
				(type default)
			)
			(layer "B.Fab")
		)
		(fp_line
			(start -0.67945 -0.3048)
			(end -0.67945 0.3048)
			(stroke
				(width 0.1)
				(type default)
			)
			(layer "B.Fab")
		)
		(fp_line
			(start -0.12065 -0.3048)
			(end -0.67945 -0.3048)
			(stroke
				(width 0.1)
				(type default)
			)
			(layer "B.Fab")
		)
		(fp_line
			(start 0.12065 -0.305054)
			(end 0.12065 -0.2794)
			(stroke
				(width 0.1)
				(type default)
			)
			(layer "B.Fab")
		)
		(fp_line
			(start 0.67945 -0.305054)
			(end 0.12065 -0.305054)
			(stroke
				(width 0.1)
				(type default)
			)
			(layer "B.Fab")
		)
		(pad "1" smd circle
			(at 0.40005 0 90)
			(size 0 0)
			(layers "B.Cu" "B.Mask" "B.Paste")
			(net "P3V3_AUX")
		)
		(pad "2" smd circle
			(at -0.40005 0 90)
			(size 0 0)
			(layers "B.Cu" "B.Mask" "B.Paste")
			(net "GND")
		)
	)
	(footprint ""
		(layer "B.Cu")
		(at 85.29955 -41.379394 180)
		(property "Reference" "R364"
			(at 0 0 0)
			(layer "B.SilkS")
			(hide yes)
			(effects
				(font
					(size 1.27 1.27)
				)
				(justify mirror)
			)
		)
		(property "Value" ""
			(at 0 0 0)
			(layer "B.Fab")
			(effects
				(font
					(size 1.27 1.27)
				)
				(justify mirror)
			)
		)
		(duplicate_pad_numbers_are_jumpers no)
		(fp_line
			(start 0.7874 0.4064)
			(end 0.7874 -0.4064)
			(stroke
				(width 0.1524)
				(type default)
			)
			(layer "B.SilkS")
		)
		(fp_line
			(start 0.7874 -0.4064)
			(end -0.7874 -0.4064)
			(stroke
				(width 0.1524)
				(type default)
			)
			(layer "B.SilkS")
		)
		(fp_line
			(start -0.7874 0.4064)
			(end 0.7874 0.4064)
			(stroke
				(width 0.1524)
				(type default)
			)
			(layer "B.SilkS")
		)
		(fp_line
			(start -0.7874 -0.4064)
			(end -0.7874 0.4064)
			(stroke
				(width 0.1524)
				(type default)
			)
			(layer "B.SilkS")
		)
		(fp_line
			(start 0.67945 0.3048)
			(end 0.67945 -0.305054)
			(stroke
				(width 0.1)
				(type default)
			)
			(layer "B.Fab")
		)
		(fp_line
			(start 0.67945 -0.305054)
			(end 0.12065 -0.305054)
			(stroke
				(width 0.1)
				(type default)
			)
			(layer "B.Fab")
		)
		(fp_line
			(start 0.12065 0.3048)
			(end 0.67945 0.3048)
			(stroke
				(width 0.1)
				(type default)
			)
			(layer "B.Fab")
		)
		(fp_line
			(start 0.12065 0.2794)
			(end 0.12065 0.3048)
			(stroke
				(width 0.1)
				(type default)
			)
			(layer "B.Fab")
		)
		(fp_line
			(start 0.12065 -0.2794)
			(end -0.12065 -0.2794)
			(stroke
				(width 0.1)
				(type default)
			)
			(layer "B.Fab")
		)
		(fp_line
			(start 0.12065 -0.305054)
			(end 0.12065 -0.2794)
			(stroke
				(width 0.1)
				(type default)
			)
			(layer "B.Fab")
		)
		(fp_line
			(start -0.120396 0.3048)
			(end -0.120396 0.2794)
			(stroke
				(width 0.1)
				(type default)
			)
			(layer "B.Fab")
		)
		(fp_line
			(start -0.120396 0.2794)
			(end 0.12065 0.2794)
			(stroke
				(width 0.1)
				(type default)
			)
			(layer "B.Fab")
		)
		(fp_line
			(start -0.12065 -0.2794)
			(end -0.12065 -0.3048)
			(stroke
				(width 0.1)
				(type default)
			)
			(layer "B.Fab")
		)
		(fp_line
			(start -0.12065 -0.3048)
			(end -0.67945 -0.3048)
			(stroke
				(width 0.1)
				(type default)
			)
			(layer "B.Fab")
		)
		(fp_line
			(start -0.67945 0.3048)
			(end -0.120396 0.3048)
			(stroke
				(width 0.1)
				(type default)
			)
			(layer "B.Fab")
		)
		(fp_line
			(start -0.67945 -0.3048)
			(end -0.67945 0.3048)
			(stroke
				(width 0.1)
				(type default)
			)
			(layer "B.Fab")
		)
		(pad "1" smd circle
			(at 0.40005 0)
			(size 0 0)
			(layers "B.Cu" "B.Mask" "B.Paste")
			(net "M_BMC_DDR4_MA<13>")
		)
		(pad "2" smd circle
			(at -0.40005 0)
			(size 0 0)
			(layers "B.Cu" "B.Mask" "B.Paste")
			(net "P1V2_AUX")
		)
	)
	(footprint ""
		(layer "B.Cu")
		(at 38.7223 -52.779676 -90)
		(property "Reference" "R278"
			(at 0 0 90)
			(layer "B.SilkS")
			(hide yes)
			(effects
				(font
					(size 1.27 1.27)
				)
				(justify mirror)
			)
		)
		(property "Value" ""
			(at 0 0 90)
			(layer "B.Fab")
			(effects
				(font
					(size 1.27 1.27)
				)
				(justify mirror)
			)
		)
		(duplicate_pad_numbers_are_jumpers no)
		(fp_line
			(start -0.7874 0.4064)
			(end 0.7874 0.4064)
			(stroke
				(width 0.1524)
				(type default)
			)
			(layer "B.SilkS")
		)
		(fp_line
			(start 0.7874 0.4064)
			(end 0.7874 -0.4064)
			(stroke
				(width 0.1524)
				(type default)
			)
			(layer "B.SilkS")
		)
		(fp_line
			(start -0.7874 -0.4064)
			(end -0.7874 0.4064)
			(stroke
				(width 0.1524)
				(type default)
			)
			(layer "B.SilkS")
		)
		(fp_line
			(start 0.7874 -0.4064)
			(end -0.7874 -0.4064)
			(stroke
				(width 0.1524)
				(type default)
			)
			(layer "B.SilkS")
		)
		(fp_line
			(start -0.67945 0.3048)
			(end -0.120396 0.3048)
			(stroke
				(width 0.1)
				(type default)
			)
			(layer "B.Fab")
		)
		(fp_line
			(start -0.120396 0.3048)
			(end -0.120396 0.2794)
			(stroke
				(width 0.1)
				(type default)
			)
			(layer "B.Fab")
		)
		(fp_line
			(start 0.12065 0.3048)
			(end 0.67945 0.3048)
			(stroke
				(width 0.1)
				(type default)
			)
			(layer "B.Fab")
		)
		(fp_line
			(start 0.67945 0.3048)
			(end 0.67945 -0.305054)
			(stroke
				(width 0.1)
				(type default)
			)
			(layer "B.Fab")
		)
		(fp_line
			(start -0.120396 0.2794)
			(end 0.12065 0.2794)
			(stroke
				(width 0.1)
				(type default)
			)
			(layer "B.Fab")
		)
		(fp_line
			(start 0.12065 0.2794)
			(end 0.12065 0.3048)
			(stroke
				(width 0.1)
				(type default)
			)
			(layer "B.Fab")
		)
		(fp_line
			(start -0.12065 -0.2794)
			(end -0.12065 -0.3048)
			(stroke
				(width 0.1)
				(type default)
			)
			(layer "B.Fab")
		)
		(fp_line
			(start 0.12065 -0.2794)
			(end -0.12065 -0.2794)
			(stroke
				(width 0.1)
				(type default)
			)
			(layer "B.Fab")
		)
		(fp_line
			(start -0.67945 -0.3048)
			(end -0.67945 0.3048)
			(stroke
				(width 0.1)
				(type default)
			)
			(layer "B.Fab")
		)
		(fp_line
			(start -0.12065 -0.3048)
			(end -0.67945 -0.3048)
			(stroke
				(width 0.1)
				(type default)
			)
			(layer "B.Fab")
		)
		(fp_line
			(start 0.12065 -0.305054)
			(end 0.12065 -0.2794)
			(stroke
				(width 0.1)
				(type default)
			)
			(layer "B.Fab")
		)
		(fp_line
			(start 0.67945 -0.305054)
			(end 0.12065 -0.305054)
			(stroke
				(width 0.1)
				(type default)
			)
			(layer "B.Fab")
		)
		(pad "1" smd circle
			(at 0.40005 0 90)
			(size 0 0)
			(layers "B.Cu" "B.Mask" "B.Paste")
			(net "P1V2_AUX")
		)
		(pad "2" smd circle
			(at -0.40005 0 90)
			(size 0 0)
			(layers "B.Cu" "B.Mask" "B.Paste")
			(net "P1V2_P1V0_I3C_VDDL1")
		)
	)
	(footprint ""
		(layer "B.Cu")
		(at 37.4015 -100.965)
		(property "Reference" "R467"
			(at 0 0 0)
			(layer "B.SilkS")
			(hide yes)
			(effects
				(font
					(size 1.27 1.27)
				)
				(justify mirror)
			)
		)
		(property "Value" ""
			(at 0 0 0)
			(layer "B.Fab")
			(effects
				(font
					(size 1.27 1.27)
				)
				(justify mirror)
			)
		)
		(duplicate_pad_numbers_are_jumpers no)
		(fp_line
			(start -0.7874 -0.4064)
			(end -0.7874 0.4064)
			(stroke
				(width 0.1524)
				(type default)
			)
			(layer "B.SilkS")
		)
		(fp_line
			(start -0.7874 0.4064)
			(end 0.7874 0.4064)
			(stroke
				(width 0.1524)
				(type default)
			)
			(layer "B.SilkS")
		)
		(fp_line
			(start 0.7874 -0.4064)
			(end -0.7874 -0.4064)
			(stroke
				(width 0.1524)
				(type default)
			)
			(layer "B.SilkS")
		)
		(fp_line
			(start 0.7874 0.4064)
			(end 0.7874 -0.4064)
			(stroke
				(width 0.1524)
				(type default)
			)
			(layer "B.SilkS")
		)
		(fp_line
			(start -0.67945 -0.3048)
			(end -0.67945 0.3048)
			(stroke
				(width 0.1)
				(type default)
			)
			(layer "B.Fab")
		)
		(fp_line
			(start -0.67945 0.3048)
			(end -0.120396 0.3048)
			(stroke
				(width 0.1)
				(type default)
			)
			(layer "B.Fab")
		)
		(fp_line
			(start -0.12065 -0.3048)
			(end -0.67945 -0.3048)
			(stroke
				(width 0.1)
				(type default)
			)
			(layer "B.Fab")
		)
		(fp_line
			(start -0.12065 -0.2794)
			(end -0.12065 -0.3048)
			(stroke
				(width 0.1)
				(type default)
			)
			(layer "B.Fab")
		)
		(fp_line
			(start -0.120396 0.2794)
			(end 0.12065 0.2794)
			(stroke
				(width 0.1)
				(type default)
			)
			(layer "B.Fab")
		)
		(fp_line
			(start -0.120396 0.3048)
			(end -0.120396 0.2794)
			(stroke
				(width 0.1)
				(type default)
			)
			(layer "B.Fab")
		)
		(fp_line
			(start 0.12065 -0.305054)
			(end 0.12065 -0.2794)
			(stroke
				(width 0.1)
				(type default)
			)
			(layer "B.Fab")
		)
		(fp_line
			(start 0.12065 -0.2794)
			(end -0.12065 -0.2794)
			(stroke
				(width 0.1)
				(type default)
			)
			(layer "B.Fab")
		)
		(fp_line
			(start 0.12065 0.2794)
			(end 0.12065 0.3048)
			(stroke
				(width 0.1)
				(type default)
			)
			(layer "B.Fab")
		)
		(fp_line
			(start 0.12065 0.3048)
			(end 0.67945 0.3048)
			(stroke
				(width 0.1)
				(type default)
			)
			(layer "B.Fab")
		)
		(fp_line
			(start 0.67945 -0.305054)
			(end 0.12065 -0.305054)
			(stroke
				(width 0.1)
				(type default)
			)
			(layer "B.Fab")
		)
		(fp_line
			(start 0.67945 0.3048)
			(end 0.67945 -0.305054)
			(stroke
				(width 0.1)
				(type default)
			)
			(layer "B.Fab")
		)
		(pad "1" smd circle
			(at 0.40005 0 180)
			(size 0 0)
			(layers "B.Cu" "B.Mask" "B.Paste")
			(net "PD_BIOS_MUX_EN_N")
		)
		(pad "2" smd circle
			(at -0.40005 0 180)
			(size 0 0)
			(layers "B.Cu" "B.Mask" "B.Paste")
			(net "GND")
		)
	)
	(footprint ""
		(layer "B.Cu")
		(at 68.6054 -50.292)
		(property "Reference" ""
			(at 0 0 0)
			(layer "B.SilkS")
			(hide yes)
			(effects
				(font
					(size 1.27 1.27)
				)
				(justify mirror)
			)
		)
		(property "Value" ""
			(at 0 0 0)
			(layer "B.Fab")
			(effects
				(font
					(size 1.27 1.27)
				)
				(justify mirror)
			)
		)
		(duplicate_pad_numbers_are_jumpers no)
		(pad "1" smd circle
			(at 0 0 180)
			(size 0.9906 0.9906)
			(layers "B.Cu" "B.Mask" "B.Paste")
			(net "Net_134")
		)
		(zone
			(layer "B.Cu")
			(hatch none 0.5)
			(connect_pads
				(clearance 0)
			)
			(min_thickness 0.25)
			(keepout
				(tracks not_allowed)
				(vias allowed)
				(pads allowed)
				(copperpour not_allowed)
				(footprints allowed)
			)
			(placement
				(enabled no)
				(sheetname "")
			)
			(fill
				(thermal_gap 0.5)
				(thermal_bridge_width 0.5)
				(island_removal_mode 0)
			)
			(polygon
				(pts
					(arc
						(start 70.231 -50.292)
						(mid 66.9798 -50.292)
						(end 70.231 -50.292)
					)
				)
			)
		)
	)
)
